(kicad_pcb
	(version 20241229)
	(generator "pcbnew")
	(generator_version "9.0")
	(general
		(thickness 1.6296)
		(legacy_teardrops no)
	)
	(paper "A3")
	(title_block
		(title "Thunderbolt to 10GbE adapter")
		(date "2026-04-21")
		(rev "1.1.0")
		(company "Antmicro Ltd")
		(comment 1 "www.antmicro.com")
		(comment 9 "footprints 551-555 of 703")
	)
	(layers
		(0 "F.Cu" signal)
		(4 "In1.Cu" signal)
		(6 "In2.Cu" signal)
		(8 "In3.Cu" signal)
		(10 "In4.Cu" signal)
		(12 "In5.Cu" signal)
		(14 "In6.Cu" signal)
		(2 "B.Cu" signal)
		(9 "F.Adhes" user "F.Adhesive")
		(11 "B.Adhes" user "B.Adhesive")
		(13 "F.Paste" user)
		(15 "B.Paste" user)
		(5 "F.SilkS" user "F.Silkscreen")
		(7 "B.SilkS" user "B.Silkscreen")
		(1 "F.Mask" user)
		(3 "B.Mask" user)
		(17 "Dwgs.User" user "User.Drawings")
		(19 "Cmts.User" user "User.Comments")
		(21 "Eco1.User" user "User.Eco1")
		(23 "Eco2.User" user "User.Eco2")
		(25 "Edge.Cuts" user)
		(27 "Margin" user)
		(31 "F.CrtYd" user "F.Courtyard")
		(29 "B.CrtYd" user "B.Courtyard")
		(35 "F.Fab" user)
		(33 "B.Fab" user)
	)
	(footprint "antmicro-footprints:R_0402_1005Metric"
		(layer "B.Cu")
		(at 137.350001 132.599999)
		(descr "Resistor SMD 0402")
		(tags "resistor SMD 0402")
		(property "Reference" "R15"
			(at 19.525001 -8.1 180)
			(layer "B.SilkS")
			(effects
				(font
					(size 0.7 0.7)
					(thickness 0.15)
				)
				(justify mirror)
			)
		)
		(property "Value" "R_10k_0402"
			(at -1.011843 -1.772047 180)
			(layer "B.Fab")
			(effects
				(font
					(size 0.7 0.7)
					(thickness 0.15)
				)
				(justify left bottom mirror)
			)
		)
		(property "Datasheet" "https://www.bourns.com/docs/product-datasheets/cr.pdf"
			(at 0 0 180)
			(layer "B.Fab")
			(hide yes)
			(effects
				(font
					(size 1.27 1.27)
					(thickness 0.15)
				)
				(justify mirror)
			)
		)
		(property "Description" "SMD Chip Resistor, 10 kohm, ± 1%, 62.5 mW, 0402 [1005 Metric], Thick Film, General Purpose"
			(at 0 0 180)
			(layer "B.Fab")
			(hide yes)
			(effects
				(font
					(size 1.27 1.27)
					(thickness 0.15)
				)
				(justify mirror)
			)
		)
		(property "MPN" "CR0402-FX-1002GLF"
			(at 0 0 0)
			(unlocked yes)
			(layer "B.Fab")
			(hide yes)
			(effects
				(font
					(size 1 1)
					(thickness 0.15)
				)
				(justify mirror)
			)
		)
		(property "Manufacturer" "Bourns"
			(at 0 0 0)
			(unlocked yes)
			(layer "B.Fab")
			(hide yes)
			(effects
				(font
					(size 1 1)
					(thickness 0.15)
				)
				(justify mirror)
			)
		)
		(property "License" "Apache-2.0"
			(at 0 0 0)
			(unlocked yes)
			(layer "B.Fab")
			(hide yes)
			(effects
				(font
					(size 1 1)
					(thickness 0.15)
				)
				(justify mirror)
			)
		)
		(property "Val" "10k"
			(at 0 0 0)
			(unlocked yes)
			(layer "B.Fab")
			(hide yes)
			(effects
				(font
					(size 1 1)
					(thickness 0.15)
				)
				(justify mirror)
			)
		)
		(property "Tolerance" "1%"
			(at 0 0 0)
			(unlocked yes)
			(layer "B.Fab")
			(hide yes)
			(effects
				(font
					(size 1 1)
					(thickness 0.15)
				)
				(justify mirror)
			)
		)
		(property "Author" "Antmicro"
			(at 0 0 0)
			(unlocked yes)
			(layer "B.Fab")
			(hide yes)
			(effects
				(font
					(size 1 1)
					(thickness 0.15)
				)
				(justify mirror)
			)
		)
		(sheetname "/PD and TB DC-DC/")
		(sheetfile "PD_and_TB_DC_DC.kicad_sch")
		(attr smd)
		(fp_rect
			(start -0.925 0.47)
			(end 0.925 -0.47)
			(stroke
				(width 0.05)
				(type default)
			)
			(fill no)
			(layer "B.CrtYd")
		)
		(fp_rect
			(start -0.5 0.25)
			(end 0.5 -0.25)
			(stroke
				(width 0.15)
				(type solid)
			)
			(fill no)
			(layer "B.Fab")
		)
		(fp_text user "Author: Antmicro"
			(at -0.95 -4.169 180)
			(layer "B.Fab")
			(effects
				(font
					(size 0.7 0.7)
					(thickness 0.15)
				)
				(justify left bottom mirror)
			)
		)
		(fp_text user "${REFERENCE}"
			(at -0.95 -3.168 180)
			(layer "B.Fab")
			(effects
				(font
					(size 0.7 0.7)
					(thickness 0.15)
				)
				(justify left bottom mirror)
			)
		)
		(fp_text user "License: Apache-2.0"
			(at -0.95 -5.169 180)
			(layer "B.Fab")
			(effects
				(font
					(size 0.7 0.7)
					(thickness 0.15)
				)
				(justify left bottom mirror)
			)
		)
		(pad "1" smd roundrect
			(at -0.48 0)
			(size 0.59 0.64)
			(layers "B.Cu" "B.Mask" "B.Paste")
			(roundrect_rratio 0.25)
			(net 304 "/PD and TB DC-DC/TPS_3V3")
			(pintype "passive")
		)
		(pad "2" smd roundrect
			(at 0.48 0)
			(size 0.59 0.64)
			(layers "B.Cu" "B.Mask" "B.Paste")
			(roundrect_rratio 0.25)
			(net 201 "Net-(U3-GPIO0(HD3_AMSEL))")
			(pintype "passive")
		)
	)
	(footprint "antmicro-footprints:TP_SMD_0.75mm"
		(layer "B.Cu")
		(at 158.386866 72.760117 -90)
		(property "Reference" "TP30"
			(at 9.839883 -20.713136 90)
			(layer "B.SilkS")
			(effects
				(font
					(size 0.7 0.7)
					(thickness 0.15)
				)
				(justify mirror)
			)
		)
		(property "Value" "TP_0.75mm_SMD"
			(at 0 -1.2 90)
			(layer "B.Fab")
			(effects
				(font
					(size 0.7 0.7)
					(thickness 0.15)
				)
				(justify left bottom mirror)
			)
		)
		(property "Description" "SMT test point"
			(at 0 0 90)
			(layer "B.Fab")
			(hide yes)
			(effects
				(font
					(size 1.27 1.27)
					(thickness 0.15)
				)
				(justify mirror)
			)
		)
		(property "MPN" ""
			(at 0 0 270)
			(unlocked yes)
			(layer "B.Fab")
			(hide yes)
			(effects
				(font
					(size 1 1)
					(thickness 0.15)
				)
				(justify mirror)
			)
		)
		(property "Manufacturer" ""
			(at 0 0 270)
			(unlocked yes)
			(layer "B.Fab")
			(hide yes)
			(effects
				(font
					(size 1 1)
					(thickness 0.15)
				)
				(justify mirror)
			)
		)
		(property "Author" "Antmicro"
			(at 0 0 270)
			(unlocked yes)
			(layer "B.Fab")
			(hide yes)
			(effects
				(font
					(size 1 1)
					(thickness 0.15)
				)
				(justify mirror)
			)
		)
		(property "License" "Apache-2.0"
			(at 0 0 270)
			(unlocked yes)
			(layer "B.Fab")
			(hide yes)
			(effects
				(font
					(size 1 1)
					(thickness 0.15)
				)
				(justify mirror)
			)
		)
		(sheetname "/X710-AT2 Misc/")
		(sheetfile "x710-at2-mics.kicad_sch")
		(attr exclude_from_pos_files exclude_from_bom)
		(fp_circle
			(center 0 0)
			(end 0.475 0)
			(stroke
				(width 0.05)
				(type default)
			)
			(fill no)
			(layer "B.CrtYd")
		)
		(fp_text user "License: Apache-2.0"
			(at -0.4 -5.101 90)
			(layer "B.Fab")
			(effects
				(font
					(size 0.7 0.7)
					(thickness 0.15)
				)
				(justify left bottom mirror)
			)
		)
		(fp_text user "Author: Antmicro"
			(at -0.4 -3.901 90)
			(layer "B.Fab")
			(effects
				(font
					(size 0.7 0.7)
					(thickness 0.15)
				)
				(justify left bottom mirror)
			)
		)
		(fp_text user "${REFERENCE}"
			(at -0.4 -2.7 90)
			(layer "B.Fab")
			(effects
				(font
					(size 0.7 0.7)
					(thickness 0.15)
				)
				(justify left bottom mirror)
			)
		)
		(pad "1" smd circle
			(at 0 0 270)
			(size 0.75 0.75)
			(layers "B.Cu" "B.Mask")
			(net 149 "/X710-AT2 Misc/REFCLK_SEL")
			(pinfunction "1")
			(pintype "passive")
		)
	)
	(footprint "antmicro-footprints:C_0402_1005Metric"
		(layer "B.Cu")
		(at 129.979999 129.31 180)
		(descr "Capacitor SMD 0402")
		(tags "capacitor SMD 0402")
		(property "Reference" "C90"
			(at -21.900002 7.700002 0)
			(layer "B.SilkS")
			(effects
				(font
					(size 0.7 0.7)
					(thickness 0.15)
				)
				(justify mirror)
			)
		)
		(property "Value" "C_10u_0402"
			(at -1.022927 -2.155213 0)
			(layer "B.Fab")
			(effects
				(font
					(size 0.7 0.7)
					(thickness 0.15)
				)
				(justify left bottom mirror)
			)
		)
		(property "Datasheet" "https://www.yageo.com/en/Chart/Download/pdf/CC0402MRX5R5BB106"
			(at 0 0 0)
			(layer "B.Fab")
			(hide yes)
			(effects
				(font
					(size 1.27 1.27)
					(thickness 0.15)
				)
				(justify mirror)
			)
		)
		(property "Description" "SMD Multilayer Ceramic Capacitor, 10 µF, 6.3 V, 0402 [1005 Metric], ± 20%, X5R, CC Series"
			(at 0 0 0)
			(layer "B.Fab")
			(hide yes)
			(effects
				(font
					(size 1.27 1.27)
					(thickness 0.15)
				)
				(justify mirror)
			)
		)
		(property "MPN" "CC0402MRX5R5BB106"
			(at 0 0 180)
			(unlocked yes)
			(layer "B.Fab")
			(hide yes)
			(effects
				(font
					(size 1 1)
					(thickness 0.15)
				)
				(justify mirror)
			)
		)
		(property "Manufacturer" "YAGEO"
			(at 0 0 180)
			(unlocked yes)
			(layer "B.Fab")
			(hide yes)
			(effects
				(font
					(size 1 1)
					(thickness 0.15)
				)
				(justify mirror)
			)
		)
		(property "License" "Apache-2.0"
			(at 0 0 180)
			(unlocked yes)
			(layer "B.Fab")
			(hide yes)
			(effects
				(font
					(size 1 1)
					(thickness 0.15)
				)
				(justify mirror)
			)
		)
		(property "Val" "10u"
			(at 0 0 180)
			(unlocked yes)
			(layer "B.Fab")
			(hide yes)
			(effects
				(font
					(size 1 1)
					(thickness 0.15)
				)
				(justify mirror)
			)
		)
		(property "Voltage" ""
			(at 0 0 180)
			(unlocked yes)
			(layer "B.Fab")
			(hide yes)
			(effects
				(font
					(size 1 1)
					(thickness 0.15)
				)
				(justify mirror)
			)
		)
		(property "Dielectric" ""
			(at 0 0 180)
			(unlocked yes)
			(layer "B.Fab")
			(hide yes)
			(effects
				(font
					(size 1 1)
					(thickness 0.15)
				)
				(justify mirror)
			)
		)
		(property "Author" "Antmicro"
			(at 0 0 180)
			(unlocked yes)
			(layer "B.Fab")
			(hide yes)
			(effects
				(font
					(size 1 1)
					(thickness 0.15)
				)
				(justify mirror)
			)
		)
		(sheetname "/TB Controller - Power/")
		(sheetfile "tb-power.kicad_sch")
		(attr smd)
		(fp_rect
			(start -0.925 0.47)
			(end 0.925 -0.47)
			(stroke
				(width 0.05)
				(type default)
			)
			(fill no)
			(layer "B.CrtYd")
		)
		(fp_line
			(start 0.504 0.25)
			(end 0.504 -0.248)
			(stroke
				(width 0.15)
				(type solid)
			)
			(layer "B.Fab")
		)
		(fp_line
			(start 0.504 -0.248)
			(end -0.494 -0.248)
			(stroke
				(width 0.15)
				(type solid)
			)
			(layer "B.Fab")
		)
		(fp_line
			(start -0.494 0.25)
			(end 0.504 0.25)
			(stroke
				(width 0.15)
				(type solid)
			)
			(layer "B.Fab")
		)
		(fp_line
			(start -0.494 -0.248)
			(end -0.494 0.25)
			(stroke
				(width 0.15)
				(type solid)
			)
			(layer "B.Fab")
		)
		(fp_text user "Author: Antmicro"
			(at -0.939 -3.399 0)
			(layer "B.Fab")
			(effects
				(font
					(size 0.7 0.7)
					(thickness 0.15)
				)
				(justify left bottom mirror)
			)
		)
		(fp_text user "${REFERENCE}"
			(at -0.939 -4.599 0)
			(layer "B.Fab")
			(effects
				(font
					(size 0.7 0.7)
					(thickness 0.15)
				)
				(justify left bottom mirror)
			)
		)
		(fp_text user "License: Apache-2.0"
			(at -0.939 -5.799 0)
			(layer "B.Fab")
			(effects
				(font
					(size 0.7 0.7)
					(thickness 0.15)
				)
				(justify left bottom mirror)
			)
		)
		(pad "1" smd roundrect
			(at -0.48 0 180)
			(size 0.59 0.64)
			(layers "B.Cu" "B.Mask" "B.Paste")
			(roundrect_rratio 0.25)
			(net 23 "GND")
			(pintype "passive")
		)
		(pad "2" smd roundrect
			(at 0.48 0 180)
			(size 0.59 0.64)
			(layers "B.Cu" "B.Mask" "B.Paste")
			(roundrect_rratio 0.25)
			(net 180 "Net-(U4A-VCC0P9_LVR_SENSE)")
			(pintype "passive")
		)
	)
	(footprint "antmicro-footprints:R_0402_1005Metric"
		(layer "B.Cu")
		(at 126.219998 119.941002 90)
		(descr "Resistor SMD 0402")
		(tags "resistor SMD 0402")
		(property "Reference" "R70"
			(at 7.700002 21.900002 270)
			(layer "B.SilkS")
			(effects
				(font
					(size 0.7 0.7)
					(thickness 0.15)
				)
				(justify mirror)
			)
		)
		(property "Value" "R_3k01_0402"
			(at -1.011843 -1.772047 270)
			(layer "B.Fab")
			(effects
				(font
					(size 0.7 0.7)
					(thickness 0.15)
				)
				(justify left bottom mirror)
			)
		)
		(property "Datasheet" "https://www.bourns.com/docs/product-datasheets/cr.pdf"
			(at 0 0 270)
			(layer "B.Fab")
			(hide yes)
			(effects
				(font
					(size 1.27 1.27)
					(thickness 0.15)
				)
				(justify mirror)
			)
		)
		(property "Description" "SMD Chip Resistor, 3.01 kohm, ± 1%, 62.5 mW, 0402 [1005 Metric], Thick Film, General Purpose"
			(at 0 0 270)
			(layer "B.Fab")
			(hide yes)
			(effects
				(font
					(size 1.27 1.27)
					(thickness 0.15)
				)
				(justify mirror)
			)
		)
		(property "MPN" "CR0402-FX-3011GLF"
			(at 0 0 90)
			(unlocked yes)
			(layer "B.Fab")
			(hide yes)
			(effects
				(font
					(size 1 1)
					(thickness 0.15)
				)
				(justify mirror)
			)
		)
		(property "Manufacturer" "Bourns"
			(at 0 0 90)
			(unlocked yes)
			(layer "B.Fab")
			(hide yes)
			(effects
				(font
					(size 1 1)
					(thickness 0.15)
				)
				(justify mirror)
			)
		)
		(property "License" "Apache-2.0"
			(at 0 0 90)
			(unlocked yes)
			(layer "B.Fab")
			(hide yes)
			(effects
				(font
					(size 1 1)
					(thickness 0.15)
				)
				(justify mirror)
			)
		)
		(property "Val" "3k01"
			(at 0 0 90)
			(unlocked yes)
			(layer "B.Fab")
			(hide yes)
			(effects
				(font
					(size 1 1)
					(thickness 0.15)
				)
				(justify mirror)
			)
		)
		(property "Tolerance" "1%"
			(at 0 0 90)
			(unlocked yes)
			(layer "B.Fab")
			(hide yes)
			(effects
				(font
					(size 1 1)
					(thickness 0.15)
				)
				(justify mirror)
			)
		)
		(property "Author" "Antmicro"
			(at 0 0 90)
			(unlocked yes)
			(layer "B.Fab")
			(hide yes)
			(effects
				(font
					(size 1 1)
					(thickness 0.15)
				)
				(justify mirror)
			)
		)
		(sheetname "/TB Controller/")
		(sheetfile "tb.kicad_sch")
		(attr smd)
		(fp_rect
			(start -0.925 0.47)
			(end 0.925 -0.47)
			(stroke
				(width 0.05)
				(type default)
			)
			(fill no)
			(layer "B.CrtYd")
		)
		(fp_rect
			(start -0.5 0.25)
			(end 0.5 -0.25)
			(stroke
				(width 0.15)
				(type solid)
			)
			(fill no)
			(layer "B.Fab")
		)
		(fp_text user "Author: Antmicro"
			(at -0.95 -4.169 270)
			(layer "B.Fab")
			(effects
				(font
					(size 0.7 0.7)
					(thickness 0.15)
				)
				(justify left bottom mirror)
			)
		)
		(fp_text user "${REFERENCE}"
			(at -0.95 -3.168 270)
			(layer "B.Fab")
			(effects
				(font
					(size 0.7 0.7)
					(thickness 0.15)
				)
				(justify left bottom mirror)
			)
		)
		(fp_text user "License: Apache-2.0"
			(at -0.95 -5.169 270)
			(layer "B.Fab")
			(effects
				(font
					(size 0.7 0.7)
					(thickness 0.15)
				)
				(justify left bottom mirror)
			)
		)
		(pad "1" smd roundrect
			(at -0.48 0 90)
			(size 0.59 0.64)
			(layers "B.Cu" "B.Mask" "B.Paste")
			(roundrect_rratio 0.25)
			(net 183 "Net-(U4B-PCIE_RBIAS)")
			(pintype "passive")
		)
		(pad "2" smd roundrect
			(at 0.48 0 90)
			(size 0.59 0.64)
			(layers "B.Cu" "B.Mask" "B.Paste")
			(roundrect_rratio 0.25)
			(net 23 "GND")
			(pintype "passive")
		)
	)
	(footprint "antmicro-footprints:R_0402_1005Metric"
		(layer "B.Cu")
		(at 138.35 135.6)
		(descr "Resistor SMD 0402")
		(tags "resistor SMD 0402")
		(property "Reference" "R23"
			(at 19.525001 -8.1 180)
			(layer "B.SilkS")
			(effects
				(font
					(size 0.7 0.7)
					(thickness 0.15)
				)
				(justify mirror)
			)
		)
		(property "Value" "R_100k_0402"
			(at -1.011843 -1.772047 180)
			(layer "B.Fab")
			(effects
				(font
					(size 0.7 0.7)
					(thickness 0.15)
				)
				(justify left bottom mirror)
			)
		)
		(property "Datasheet" "https://www.bourns.com/docs/product-datasheets/cr.pdf"
			(at 0 0 180)
			(layer "B.Fab")
			(hide yes)
			(effects
				(font
					(size 1.27 1.27)
					(thickness 0.15)
				)
				(justify mirror)
			)
		)
		(property "Description" "SMD Chip Resistor, 100 kohm, ± 1%, 62.5 mW, 0402 [1005 Metric], Thick Film, General Purpose"
			(at 0 0 180)
			(layer "B.Fab")
			(hide yes)
			(effects
				(font
					(size 1.27 1.27)
					(thickness 0.15)
				)
				(justify mirror)
			)
		)
		(property "MPN" "CR0402-FX-1003GLF"
			(at 0 0 0)
			(unlocked yes)
			(layer "B.Fab")
			(hide yes)
			(effects
				(font
					(size 1 1)
					(thickness 0.15)
				)
				(justify mirror)
			)
		)
		(property "Manufacturer" "Bourns"
			(at 0 0 0)
			(unlocked yes)
			(layer "B.Fab")
			(hide yes)
			(effects
				(font
					(size 1 1)
					(thickness 0.15)
				)
				(justify mirror)
			)
		)
		(property "License" "Apache-2.0"
			(at 0 0 0)
			(unlocked yes)
			(layer "B.Fab")
			(hide yes)
			(effects
				(font
					(size 1 1)
					(thickness 0.15)
				)
				(justify mirror)
			)
		)
		(property "Val" "100k"
			(at 0 0 0)
			(unlocked yes)
			(layer "B.Fab")
			(hide yes)
			(effects
				(font
					(size 1 1)
					(thickness 0.15)
				)
				(justify mirror)
			)
		)
		(property "Tolerance" "1%"
			(at 0 0 0)
			(unlocked yes)
			(layer "B.Fab")
			(hide yes)
			(effects
				(font
					(size 1 1)
					(thickness 0.15)
				)
				(justify mirror)
			)
		)
		(property "Author" "Antmicro"
			(at 0 0 0)
			(unlocked yes)
			(layer "B.Fab")
			(hide yes)
			(effects
				(font
					(size 1 1)
					(thickness 0.15)
				)
				(justify mirror)
			)
		)
		(sheetname "/PD and TB DC-DC/")
		(sheetfile "PD_and_TB_DC_DC.kicad_sch")
		(attr smd)
		(fp_rect
			(start -0.925 0.47)
			(end 0.925 -0.47)
			(stroke
				(width 0.05)
				(type default)
			)
			(fill no)
			(layer "B.CrtYd")
		)
		(fp_rect
			(start -0.5 0.25)
			(end 0.5 -0.25)
			(stroke
				(width 0.15)
				(type solid)
			)
			(fill no)
			(layer "B.Fab")
		)
		(fp_text user "License: Apache-2.0"
			(at -0.95 -5.169 180)
			(layer "B.Fab")
			(effects
				(font
					(size 0.7 0.7)
					(thickness 0.15)
				)
				(justify left bottom mirror)
			)
		)
		(fp_text user "${REFERENCE}"
			(at -0.95 -3.168 180)
			(layer "B.Fab")
			(effects
				(font
					(size 0.7 0.7)
					(thickness 0.15)
				)
				(justify left bottom mirror)
			)
		)
		(fp_text user "Author: Antmicro"
			(at -0.95 -4.169 180)
			(layer "B.Fab")
			(effects
				(font
					(size 0.7 0.7)
					(thickness 0.15)
				)
				(justify left bottom mirror)
			)
		)
		(pad "1" smd roundrect
			(at -0.48 0)
			(size 0.59 0.64)
			(layers "B.Cu" "B.Mask" "B.Paste")
			(roundrect_rratio 0.25)
			(net 206 "Net-(U3-DEBUG_CTL2(GPIO17,_I2CADDR_B5))")
			(pintype "passive")
		)
		(pad "2" smd roundrect
			(at 0.48 0)
			(size 0.59 0.64)
			(layers "B.Cu" "B.Mask" "B.Paste")
			(roundrect_rratio 0.25)
			(net 304 "/PD and TB DC-DC/TPS_3V3")
			(pintype "passive")
		)
	)
)
